# T6G (Grand Teton) — schematic netlist excerpt (pin names and nets, part order shuffled) for the footprints in the layout excerpt that follows; sources: Cadence DE-HDL packaged netlist, KiCad conversion of 04192023_DAF0TMB3IC0_F0TG_MB_C_brd_V02_OCP.brd

C871  Q_CAP_DIFFBUS  DIFF BUS_0.22UF 6.3V 20% X6S  pkg C0201  page 64 : \1\ = P5E_CPU0_P3_TX_C_DP<15> ; \2\ = P5E_CPU0_P3_TX_DP<15>
R4620  Q_RES  1K 1% EMPTY  pkg 0402LF  page 268 : A = P3V3_AUX ; B = IRQ_UV_DETECT_N
R3486  Q_RES  33.2 1% CHIP  pkg 0402LF  page 81 : A = GPU_PRSNT_N_ISO_R ; B = GPU_PRSNT_N_ISO

(kicad_pcb
	(version 20260206)
	(generator "pcbnew")
	(generator_version "10.0")
	(general
		(thickness 1.6)
		(legacy_teardrops no)
	)
	(paper "A4")
	(title_block
		(title "04192023_DAF0TMB3IC0_F0TG_MB_C_brd_V02_OCP.brd")
		(comment 1 "Grand Teton / footprints 2832-2834 of 8354")
	)
	(layers
		(0 "F.Cu" signal "TOP")
		(4 "In1.Cu" signal "GND")
		(6 "In2.Cu" signal "IN1")
		(8 "In3.Cu" signal "GND1")
		(10 "In4.Cu" signal "IN2")
		(12 "In5.Cu" signal "GND2")
		(14 "In6.Cu" signal "IN3")
		(16 "In7.Cu" signal "GND3")
		(18 "In8.Cu" signal "VCC")
		(20 "In9.Cu" signal "VCC1")
		(22 "In10.Cu" signal "GND4")
		(24 "In11.Cu" signal "IN4")
		(26 "In12.Cu" signal "GND5")
		(28 "In13.Cu" signal "IN5")
		(30 "In14.Cu" signal "GND6")
		(32 "In15.Cu" signal "IN6")
		(34 "In16.Cu" signal "GND7")
		(2 "B.Cu" signal "BOTTOM")
		(9 "F.Adhes" user "F.Adhesive")
		(11 "B.Adhes" user "B.Adhesive")
		(13 "F.Paste" user "Package Geometry/Pastemask Top")
		(15 "B.Paste" user "Package Geometry/Pastemask Bottom")
		(5 "F.SilkS" user "Ref Des/Silkscreen Top")
		(7 "B.SilkS" user "Ref Des/Silkscreen Bottom")
		(1 "F.Mask" user "Board Geometry/Soldermask Top")
		(3 "B.Mask" user "Board Geometry/Soldermask Bottom")
		(17 "Dwgs.User" user "User.Drawings")
		(19 "Cmts.User" user "User.Comments")
		(21 "Eco1.User" user "User.Eco1")
		(23 "Eco2.User" user "User.Eco2")
		(25 "Edge.Cuts" user "Board Geometry/Outline")
		(27 "Margin" user)
		(31 "F.CrtYd" user "Package Geometry/Place Bound Top")
		(29 "B.CrtYd" user "Package Geometry/Place Bound Bottom")
		(35 "F.Fab" user "Ref Des/Assembly Top")
		(33 "B.Fab" user "Ref Des/Assembly Bottom")
	)
	(footprint ""
		(layer "F.Cu")
		(at 392.840972 -387.853428)
		(property "Reference" "C871"
			(at 0 0 0)
			(layer "F.SilkS")
			(hide yes)
			(effects
				(font
					(size 1.27 1.27)
				)
			)
		)
		(property "Value" ""
			(at 0 0 0)
			(layer "F.Fab")
			(effects
				(font
					(size 1.27 1.27)
				)
			)
		)
		(duplicate_pad_numbers_are_jumpers no)
		(fp_line
			(start -0.299974 -0.150114)
			(end 0.299974 -0.150114)
			(stroke
				(width 0.1)
				(type default)
			)
			(layer "F.Fab")
		)
		(fp_line
			(start -0.299974 0.150114)
			(end -0.299974 -0.150114)
			(stroke
				(width 0.1)
				(type default)
			)
			(layer "F.Fab")
		)
		(fp_line
			(start 0.299974 -0.150114)
			(end 0.299974 0.150114)
			(stroke
				(width 0.1)
				(type default)
			)
			(layer "F.Fab")
		)
		(fp_line
			(start 0.299974 0.150114)
			(end -0.299974 0.150114)
			(stroke
				(width 0.1)
				(type default)
			)
			(layer "F.Fab")
		)
		(pad "1" smd rect
			(at -0.2667 0)
			(size 0.3048 0.381)
			(layers "F.Cu" "F.Mask" "F.Paste")
			(net "P5E_CPU0_P3_TX_C_DP<15>")
		)
		(pad "2" smd rect
			(at 0.2667 0)
			(size 0.3048 0.381)
			(layers "F.Cu" "F.Mask" "F.Paste")
			(net "P5E_CPU0_P3_TX_DP<15>")
		)
	)
	(footprint ""
		(layer "F.Cu")
		(at 150.373334 -121.826274)
		(property "Reference" "R4620"
			(at 0 0 0)
			(layer "F.SilkS")
			(hide yes)
			(effects
				(font
					(size 1.27 1.27)
				)
			)
		)
		(property "Value" ""
			(at 0 0 0)
			(layer "F.Fab")
			(effects
				(font
					(size 1.27 1.27)
				)
			)
		)
		(duplicate_pad_numbers_are_jumpers no)
		(fp_line
			(start -0.7874 -0.4064)
			(end 0.7874 -0.4064)
			(stroke
				(width 0.1524)
				(type default)
			)
			(layer "F.SilkS")
		)
		(fp_line
			(start -0.7874 0.4064)
			(end -0.7874 -0.4064)
			(stroke
				(width 0.1524)
				(type default)
			)
			(layer "F.SilkS")
		)
		(fp_line
			(start 0.7874 -0.4064)
			(end 0.7874 0.4064)
			(stroke
				(width 0.1524)
				(type default)
			)
			(layer "F.SilkS")
		)
		(fp_line
			(start 0.7874 0.4064)
			(end -0.7874 0.4064)
			(stroke
				(width 0.1524)
				(type default)
			)
			(layer "F.SilkS")
		)
		(fp_line
			(start -0.67945 -0.305054)
			(end -0.12065 -0.305054)
			(stroke
				(width 0.1)
				(type default)
			)
			(layer "F.Fab")
		)
		(fp_line
			(start -0.67945 0.3048)
			(end -0.67945 -0.305054)
			(stroke
				(width 0.1)
				(type default)
			)
			(layer "F.Fab")
		)
		(fp_line
			(start -0.12065 -0.305054)
			(end -0.12065 -0.2794)
			(stroke
				(width 0.1)
				(type default)
			)
			(layer "F.Fab")
		)
		(fp_line
			(start -0.12065 -0.2794)
			(end 0.12065 -0.2794)
			(stroke
				(width 0.1)
				(type default)
			)
			(layer "F.Fab")
		)
		(fp_line
			(start -0.12065 0.2794)
			(end -0.12065 0.3048)
			(stroke
				(width 0.1)
				(type default)
			)
			(layer "F.Fab")
		)
		(fp_line
			(start -0.12065 0.3048)
			(end -0.67945 0.3048)
			(stroke
				(width 0.1)
				(type default)
			)
			(layer "F.Fab")
		)
		(fp_line
			(start 0.120396 0.2794)
			(end -0.12065 0.2794)
			(stroke
				(width 0.1)
				(type default)
			)
			(layer "F.Fab")
		)
		(fp_line
			(start 0.120396 0.3048)
			(end 0.120396 0.2794)
			(stroke
				(width 0.1)
				(type default)
			)
			(layer "F.Fab")
		)
		(fp_line
			(start 0.12065 -0.3048)
			(end 0.67945 -0.3048)
			(stroke
				(width 0.1)
				(type default)
			)
			(layer "F.Fab")
		)
		(fp_line
			(start 0.12065 -0.2794)
			(end 0.12065 -0.3048)
			(stroke
				(width 0.1)
				(type default)
			)
			(layer "F.Fab")
		)
		(fp_line
			(start 0.67945 -0.3048)
			(end 0.67945 0.3048)
			(stroke
				(width 0.1)
				(type default)
			)
			(layer "F.Fab")
		)
		(fp_line
			(start 0.67945 0.3048)
			(end 0.120396 0.3048)
			(stroke
				(width 0.1)
				(type default)
			)
			(layer "F.Fab")
		)
		(pad "1" smd circle
			(at -0.40005 0)
			(size 0 0)
			(layers "F.Cu" "F.Mask" "F.Paste")
			(net "P3V3_AUX")
		)
		(pad "2" smd circle
			(at 0.40005 0)
			(size 0 0)
			(layers "F.Cu" "F.Mask" "F.Paste")
			(net "IRQ_UV_DETECT_N")
		)
	)
	(footprint ""
		(layer "F.Cu")
		(at 163.738814 -119.345202 180)
		(property "Reference" "R3486"
			(at 0 0 180)
			(layer "F.SilkS")
			(hide yes)
			(effects
				(font
					(size 1.27 1.27)
				)
			)
		)
		(property "Value" ""
			(at 0 0 180)
			(layer "F.Fab")
			(effects
				(font
					(size 1.27 1.27)
				)
			)
		)
		(duplicate_pad_numbers_are_jumpers no)
		(fp_line
			(start 0.7874 0.4064)
			(end -0.7874 0.4064)
			(stroke
				(width 0.1524)
				(type default)
			)
			(layer "F.SilkS")
		)
		(fp_line
			(start 0.7874 -0.4064)
			(end 0.7874 0.4064)
			(stroke
				(width 0.1524)
				(type default)
			)
			(layer "F.SilkS")
		)
		(fp_line
			(start -0.7874 0.4064)
			(end -0.7874 -0.4064)
			(stroke
				(width 0.1524)
				(type default)
			)
			(layer "F.SilkS")
		)
		(fp_line
			(start -0.7874 -0.4064)
			(end 0.7874 -0.4064)
			(stroke
				(width 0.1524)
				(type default)
			)
			(layer "F.SilkS")
		)
		(fp_line
			(start 0.67945 0.3048)
			(end 0.120396 0.3048)
			(stroke
				(width 0.1)
				(type default)
			)
			(layer "F.Fab")
		)
		(fp_line
			(start 0.67945 -0.3048)
			(end 0.67945 0.3048)
			(stroke
				(width 0.1)
				(type default)
			)
			(layer "F.Fab")
		)
		(fp_line
			(start 0.12065 -0.2794)
			(end 0.12065 -0.3048)
			(stroke
				(width 0.1)
				(type default)
			)
			(layer "F.Fab")
		)
		(fp_line
			(start 0.12065 -0.3048)
			(end 0.67945 -0.3048)
			(stroke
				(width 0.1)
				(type default)
			)
			(layer "F.Fab")
		)
		(fp_line
			(start 0.120396 0.3048)
			(end 0.120396 0.2794)
			(stroke
				(width 0.1)
				(type default)
			)
			(layer "F.Fab")
		)
		(fp_line
			(start 0.120396 0.2794)
			(end -0.12065 0.2794)
			(stroke
				(width 0.1)
				(type default)
			)
			(layer "F.Fab")
		)
		(fp_line
			(start -0.12065 0.3048)
			(end -0.67945 0.3048)
			(stroke
				(width 0.1)
				(type default)
			)
			(layer "F.Fab")
		)
		(fp_line
			(start -0.12065 0.2794)
			(end -0.12065 0.3048)
			(stroke
				(width 0.1)
				(type default)
			)
			(layer "F.Fab")
		)
		(fp_line
			(start -0.12065 -0.2794)
			(end 0.12065 -0.2794)
			(stroke
				(width 0.1)
				(type default)
			)
			(layer "F.Fab")
		)
		(fp_line
			(start -0.12065 -0.305054)
			(end -0.12065 -0.2794)
			(stroke
				(width 0.1)
				(type default)
			)
			(layer "F.Fab")
		)
		(fp_line
			(start -0.67945 0.3048)
			(end -0.67945 -0.305054)
			(stroke
				(width 0.1)
				(type default)
			)
			(layer "F.Fab")
		)
		(fp_line
			(start -0.67945 -0.305054)
			(end -0.12065 -0.305054)
			(stroke
				(width 0.1)
				(type default)
			)
			(layer "F.Fab")
		)
		(pad "1" smd circle
			(at -0.40005 0 180)
			(size 0 0)
			(layers "F.Cu" "F.Mask" "F.Paste")
			(net "GPU_PRSNT_N_ISO_R")
		)
		(pad "2" smd circle
			(at 0.40005 0 180)
			(size 0 0)
			(layers "F.Cu" "F.Mask" "F.Paste")
			(net "GPU_PRSNT_N_ISO")
		)
	)
)
